(kicad_pcb
	(version 20260206)
	(generator "pcbnew")
	(generator_version "10.0")
	(general
		(thickness 1.6)
		(legacy_teardrops no)
	)
	(paper "A4")
	(title_block
		(title "peb — Lightning_PEB_BRD.brd")
		(comment 1 "Lightning (Wiwynn / Facebook NVMe JBOF) / footprints 2085-2092 of 2563")
	)
	(layers
		(0 "F.Cu" signal "TOP")
		(4 "In1.Cu" signal "L2GND")
		(6 "In2.Cu" signal "L3")
		(8 "In3.Cu" signal "L4VCC")
		(10 "In4.Cu" signal "L5VCC")
		(12 "In5.Cu" signal "L6")
		(14 "In6.Cu" signal "L7GND")
		(2 "B.Cu" signal "BOTTOM")
		(9 "F.Adhes" user "F.Adhesive")
		(11 "B.Adhes" user "B.Adhesive")
		(13 "F.Paste" user "Package Geometry/Pastemask Top")
		(15 "B.Paste" user "Package Geometry/Pastemask Bottom")
		(5 "F.SilkS" user "Ref Des/Silkscreen Top")
		(7 "B.SilkS" user "Ref Des/Silkscreen Bottom")
		(1 "F.Mask" user "Board Geometry/Soldermask Top")
		(3 "B.Mask" user "Board Geometry/Soldermask Bottom")
		(17 "Dwgs.User" user "User.Drawings")
		(19 "Cmts.User" user "User.Comments")
		(21 "Eco1.User" user "User.Eco1")
		(23 "Eco2.User" user "User.Eco2")
		(25 "Edge.Cuts" user "Board Geometry/Outline")
		(27 "Margin" user)
		(31 "F.CrtYd" user "Package Geometry/Place Bound Top")
		(29 "B.CrtYd" user "Package Geometry/Place Bound Bottom")
		(35 "F.Fab" user "Ref Des/Assembly Top")
		(33 "B.Fab" user "Ref Des/Assembly Bottom")
	)
	(footprint ""
		(layer "B.Cu")
		(at 43.942 -140.335)
		(property "Reference" "TP145"
			(at 0 0 0)
			(layer "B.SilkS")
			(hide yes)
			(effects
				(font
					(size 1.27 1.27)
				)
				(justify mirror)
			)
		)
		(property "Value" "TPAD28-2-GP"
			(at 0.0127 -1.6637 0)
			(unlocked yes)
			(layer "B.Fab")
			(hide yes)
			(effects
				(font
					(size 1.016 1.016)
					(thickness 0.1524)
				)
				(justify mirror)
			)
		)
		(property "Device Type" "TPAD28"
			(at 0.0127 -3.1877 0)
			(unlocked yes)
			(layer "B.Fab")
			(hide yes)
			(effects
				(font
					(size 1.016 1.016)
					(thickness 0.1524)
				)
				(justify mirror)
			)
		)
		(duplicate_pad_numbers_are_jumpers no)
		(fp_poly
			(pts
				(arc
					(start 0.3556 0)
					(mid -0.3556 0)
					(end 0.3556 0)
				)
			)
			(stroke
				(width 0)
				(type default)
			)
			(fill no)
			(layer "B.CrtYd")
		)
		(fp_poly
			(pts
				(arc
					(start 0.6096 0)
					(mid -0.6096 0)
					(end 0.6096 0)
				)
			)
			(stroke
				(width 0)
				(type default)
			)
			(fill no)
			(layer "B.Fab")
		)
		(pad "1" smd circle
			(at 0 0 180)
			(size 0.7112 0.7112)
			(layers "B.Cu" "B.Mask" "B.Paste")
			(net "TP_GPIOP0")
		)
	)
	(footprint ""
		(layer "B.Cu")
		(at 20.955 -132.715 -90)
		(property "Reference" "R639"
			(at 0 0 90)
			(layer "B.SilkS")
			(hide yes)
			(effects
				(font
					(size 1.27 1.27)
				)
				(justify mirror)
			)
		)
		(property "Value" "0R2J-2-GP"
			(at -0.064008 -3.993896 270)
			(unlocked yes)
			(layer "B.Fab")
			(hide yes)
			(effects
				(font
					(size 1.016 1.016)
					(thickness 0.1524)
				)
				(justify mirror)
			)
		)
		(property "Device Type" "R402H16"
			(at -0.064008 -5.517896 270)
			(unlocked yes)
			(layer "B.Fab")
			(hide yes)
			(effects
				(font
					(size 1.016 1.016)
					(thickness 0.1524)
				)
				(justify mirror)
			)
		)
		(duplicate_pad_numbers_are_jumpers no)
		(fp_line
			(start -0.508 -0.9398)
			(end 0.508 -0.9398)
			(stroke
				(width 0.1524)
				(type default)
			)
			(layer "B.SilkS")
		)
		(fp_line
			(start 0.508 -0.9398)
			(end 0.508 0.9398)
			(stroke
				(width 0.1524)
				(type default)
			)
			(layer "B.SilkS")
		)
		(fp_rect
			(start 0.508 0.9398)
			(end -0.508 -0.9398)
			(stroke
				(width 0)
				(type default)
			)
			(fill no)
			(layer "B.CrtYd")
		)
		(fp_rect
			(start 0.508 0.9398)
			(end -0.508 -0.9398)
			(stroke
				(width 0)
				(type default)
			)
			(fill no)
			(layer "B.Fab")
		)
		(pad "1" smd custom
			(at 0 -0.4445 90)
			(size 0.1397 0.1397)
			(layers "B.Cu" "B.Mask" "B.Paste")
			(net "FLA_CS")
			(options
				(clearance outline)
				(anchor circle)
			)
			(primitives
				(gr_poly
					(pts
						(arc
							(start -0.1778 0.2794)
							(mid -0.249642 0.249642)
							(end -0.2794 0.1778)
						)
						(arc
							(start -0.2794 -0.1778)
							(mid -0.249642 -0.249642)
							(end -0.1778 -0.2794)
						)
						(arc
							(start 0.1778 -0.2794)
							(mid 0.249642 -0.249642)
							(end 0.2794 -0.1778)
						)
						(arc
							(start 0.2794 0.1778)
							(mid 0.249642 0.249642)
							(end 0.1778 0.2794)
						)
					)
					(width 0)
					(fill yes)
				)
			)
		)
		(pad "2" smd custom
			(at 0 0.4445 90)
			(size 0.1397 0.1397)
			(layers "B.Cu" "B.Mask" "B.Paste")
			(net "FLA_CS_R")
			(options
				(clearance outline)
				(anchor circle)
			)
			(primitives
				(gr_poly
					(pts
						(arc
							(start -0.1778 0.2794)
							(mid -0.249642 0.249642)
							(end -0.2794 0.1778)
						)
						(arc
							(start -0.2794 -0.1778)
							(mid -0.249642 -0.249642)
							(end -0.1778 -0.2794)
						)
						(arc
							(start 0.1778 -0.2794)
							(mid 0.249642 -0.249642)
							(end 0.2794 -0.1778)
						)
						(arc
							(start 0.2794 0.1778)
							(mid 0.249642 0.249642)
							(end 0.1778 0.2794)
						)
					)
					(width 0)
					(fill yes)
				)
			)
		)
	)
	(footprint ""
		(layer "B.Cu")
		(at 41.656 -130.175 -90)
		(property "Reference" "C206"
			(at 0 0 90)
			(layer "B.SilkS")
			(hide yes)
			(effects
				(font
					(size 1.27 1.27)
				)
				(justify mirror)
			)
		)
		(property "Value" "SC1U10V2KX-4-GP"
			(at -1.1811 -2.7051 270)
			(unlocked yes)
			(layer "B.Fab")
			(hide yes)
			(effects
				(font
					(size 1.016 1.016)
					(thickness 0.1524)
				)
				(justify mirror)
			)
		)
		(property "Device Type" "C402H22"
			(at -1.1811 -4.2291 270)
			(unlocked yes)
			(layer "B.Fab")
			(hide yes)
			(effects
				(font
					(size 1.016 1.016)
					(thickness 0.1524)
				)
				(justify mirror)
			)
		)
		(duplicate_pad_numbers_are_jumpers no)
		(fp_rect
			(start 0.4318 0.9525)
			(end -0.4318 -0.9525)
			(stroke
				(width 0)
				(type default)
			)
			(fill no)
			(layer "B.CrtYd")
		)
		(fp_rect
			(start 0.4318 0.9525)
			(end -0.4318 -0.9525)
			(stroke
				(width 0)
				(type default)
			)
			(fill no)
			(layer "B.Fab")
		)
		(pad "1" smd custom
			(at 0 -0.4445 90)
			(size 0.1524 0.1524)
			(layers "B.Cu" "B.Mask" "B.Paste")
			(net "P1V26_STBY")
			(options
				(clearance outline)
				(anchor circle)
			)
			(primitives
				(gr_poly
					(pts
						(arc
							(start 0.3048 0.2032)
							(mid 0.275042 0.275042)
							(end 0.2032 0.3048)
						)
						(arc
							(start -0.2032 0.3048)
							(mid -0.275042 0.275042)
							(end -0.3048 0.2032)
						)
						(arc
							(start -0.3048 -0.2032)
							(mid -0.275042 -0.275042)
							(end -0.2032 -0.3048)
						)
						(arc
							(start 0.2032 -0.3048)
							(mid 0.275042 -0.275042)
							(end 0.3048 -0.2032)
						)
					)
					(width 0)
					(fill yes)
				)
			)
		)
		(pad "2" smd custom
			(at 0 0.4445 90)
			(size 0.1524 0.1524)
			(layers "B.Cu" "B.Mask" "B.Paste")
			(net "GND")
			(options
				(clearance outline)
				(anchor circle)
			)
			(primitives
				(gr_poly
					(pts
						(arc
							(start 0.3048 0.2032)
							(mid 0.275042 0.275042)
							(end 0.2032 0.3048)
						)
						(arc
							(start -0.2032 0.3048)
							(mid -0.275042 0.275042)
							(end -0.3048 0.2032)
						)
						(arc
							(start -0.3048 -0.2032)
							(mid -0.275042 -0.275042)
							(end -0.2032 -0.3048)
						)
						(arc
							(start 0.2032 -0.3048)
							(mid 0.275042 -0.275042)
							(end 0.3048 -0.2032)
						)
					)
					(width 0)
					(fill yes)
				)
			)
		)
	)
	(footprint ""
		(layer "B.Cu")
		(at 225.679 -20.447)
		(property "Reference" "R3705"
			(at 0 0 0)
			(layer "B.SilkS")
			(hide yes)
			(effects
				(font
					(size 1.27 1.27)
				)
				(justify mirror)
			)
		)
		(property "Value" "4K7R2F-GP"
			(at -0.064008 -3.993896 0)
			(unlocked yes)
			(layer "B.Fab")
			(hide yes)
			(effects
				(font
					(size 1.016 1.016)
					(thickness 0.1524)
				)
				(justify mirror)
			)
		)
		(property "Device Type" "R402H16"
			(at -0.064008 -5.517896 0)
			(unlocked yes)
			(layer "B.Fab")
			(hide yes)
			(effects
				(font
					(size 1.016 1.016)
					(thickness 0.1524)
				)
				(justify mirror)
			)
		)
		(duplicate_pad_numbers_are_jumpers no)
		(fp_line
			(start -0.508 -0.9398)
			(end 0.508 -0.9398)
			(stroke
				(width 0.1524)
				(type default)
			)
			(layer "B.SilkS")
		)
		(fp_line
			(start 0.508 -0.9398)
			(end 0.508 0.9398)
			(stroke
				(width 0.1524)
				(type default)
			)
			(layer "B.SilkS")
		)
		(fp_rect
			(start 0.508 0.9398)
			(end -0.508 -0.9398)
			(stroke
				(width 0)
				(type default)
			)
			(fill no)
			(layer "B.CrtYd")
		)
		(fp_rect
			(start 0.508 0.9398)
			(end -0.508 -0.9398)
			(stroke
				(width 0)
				(type default)
			)
			(fill no)
			(layer "B.Fab")
		)
		(pad "1" smd custom
			(at 0 -0.4445 180)
			(size 0.1397 0.1397)
			(layers "B.Cu" "B.Mask" "B.Paste")
			(net "HOST5_RST_N_LS")
			(options
				(clearance outline)
				(anchor circle)
			)
			(primitives
				(gr_poly
					(pts
						(arc
							(start -0.1778 0.2794)
							(mid -0.249642 0.249642)
							(end -0.2794 0.1778)
						)
						(arc
							(start -0.2794 -0.1778)
							(mid -0.249642 -0.249642)
							(end -0.1778 -0.2794)
						)
						(arc
							(start 0.1778 -0.2794)
							(mid 0.249642 -0.249642)
							(end 0.2794 -0.1778)
						)
						(arc
							(start 0.2794 0.1778)
							(mid 0.249642 0.249642)
							(end 0.1778 0.2794)
						)
					)
					(width 0)
					(fill yes)
				)
			)
		)
		(pad "2" smd custom
			(at 0 0.4445 180)
			(size 0.1397 0.1397)
			(layers "B.Cu" "B.Mask" "B.Paste")
			(net "DUT_VDDO")
			(options
				(clearance outline)
				(anchor circle)
			)
			(primitives
				(gr_poly
					(pts
						(arc
							(start -0.1778 0.2794)
							(mid -0.249642 0.249642)
							(end -0.2794 0.1778)
						)
						(arc
							(start -0.2794 -0.1778)
							(mid -0.249642 -0.249642)
							(end -0.1778 -0.2794)
						)
						(arc
							(start 0.1778 -0.2794)
							(mid 0.249642 -0.249642)
							(end 0.2794 -0.1778)
						)
						(arc
							(start 0.2794 0.1778)
							(mid 0.249642 0.249642)
							(end 0.1778 0.2794)
						)
					)
					(width 0)
					(fill yes)
				)
			)
		)
	)
	(footprint ""
		(layer "B.Cu")
		(at 265.4808 -9.30021 -90)
		(property "Reference" "R724"
			(at 0 0 90)
			(layer "B.SilkS")
			(hide yes)
			(effects
				(font
					(size 1.27 1.27)
				)
				(justify mirror)
			)
		)
		(property "Value" "0R2J-2-GP"
			(at -0.064008 -3.993896 270)
			(unlocked yes)
			(layer "B.Fab")
			(hide yes)
			(effects
				(font
					(size 1.016 1.016)
					(thickness 0.1524)
				)
				(justify mirror)
			)
		)
		(property "Device Type" "R402H16"
			(at -0.064008 -5.517896 270)
			(unlocked yes)
			(layer "B.Fab")
			(hide yes)
			(effects
				(font
					(size 1.016 1.016)
					(thickness 0.1524)
				)
				(justify mirror)
			)
		)
		(duplicate_pad_numbers_are_jumpers no)
		(fp_line
			(start -0.508 -0.9398)
			(end 0.508 -0.9398)
			(stroke
				(width 0.1524)
				(type default)
			)
			(layer "B.SilkS")
		)
		(fp_line
			(start 0.508 -0.9398)
			(end 0.508 0.9398)
			(stroke
				(width 0.1524)
				(type default)
			)
			(layer "B.SilkS")
		)
		(fp_rect
			(start 0.508 0.9398)
			(end -0.508 -0.9398)
			(stroke
				(width 0)
				(type default)
			)
			(fill no)
			(layer "B.CrtYd")
		)
		(fp_rect
			(start 0.508 0.9398)
			(end -0.508 -0.9398)
			(stroke
				(width 0)
				(type default)
			)
			(fill no)
			(layer "B.Fab")
		)
		(pad "1" smd custom
			(at 0 -0.4445 90)
			(size 0.1397 0.1397)
			(layers "B.Cu" "B.Mask" "B.Paste")
			(net "HOST7_RST_N_C")
			(options
				(clearance outline)
				(anchor circle)
			)
			(primitives
				(gr_poly
					(pts
						(arc
							(start -0.1778 0.2794)
							(mid -0.249642 0.249642)
							(end -0.2794 0.1778)
						)
						(arc
							(start -0.2794 -0.1778)
							(mid -0.249642 -0.249642)
							(end -0.1778 -0.2794)
						)
						(arc
							(start 0.1778 -0.2794)
							(mid 0.249642 -0.249642)
							(end 0.2794 -0.1778)
						)
						(arc
							(start 0.2794 0.1778)
							(mid 0.249642 0.249642)
							(end 0.1778 0.2794)
						)
					)
					(width 0)
					(fill yes)
				)
			)
		)
		(pad "2" smd custom
			(at 0 0.4445 90)
			(size 0.1397 0.1397)
			(layers "B.Cu" "B.Mask" "B.Paste")
			(net "P3V3_STBY")
			(options
				(clearance outline)
				(anchor circle)
			)
			(primitives
				(gr_poly
					(pts
						(arc
							(start -0.1778 0.2794)
							(mid -0.249642 0.249642)
							(end -0.2794 0.1778)
						)
						(arc
							(start -0.2794 -0.1778)
							(mid -0.249642 -0.249642)
							(end -0.1778 -0.2794)
						)
						(arc
							(start 0.1778 -0.2794)
							(mid 0.249642 -0.249642)
							(end 0.2794 -0.1778)
						)
						(arc
							(start 0.2794 0.1778)
							(mid 0.249642 0.249642)
							(end 0.1778 0.2794)
						)
					)
					(width 0)
					(fill yes)
				)
			)
		)
	)
	(footprint ""
		(layer "B.Cu")
		(at 23.90648 -137.586974 90)
		(property "Reference" "R350"
			(at 0 0 90)
			(layer "B.SilkS")
			(hide yes)
			(effects
				(font
					(size 1.27 1.27)
				)
				(justify mirror)
			)
		)
		(property "Value" "3K3R2F-2-GP"
			(at -0.064008 -3.993896 90)
			(unlocked yes)
			(layer "B.Fab")
			(hide yes)
			(effects
				(font
					(size 1.016 1.016)
					(thickness 0.1524)
				)
				(justify mirror)
			)
		)
		(property "Device Type" "R402H16"
			(at -0.064008 -5.517896 90)
			(unlocked yes)
			(layer "B.Fab")
			(hide yes)
			(effects
				(font
					(size 1.016 1.016)
					(thickness 0.1524)
				)
				(justify mirror)
			)
		)
		(duplicate_pad_numbers_are_jumpers no)
		(fp_line
			(start 0.508 -0.9398)
			(end 0.508 0.9398)
			(stroke
				(width 0.1524)
				(type default)
			)
			(layer "B.SilkS")
		)
		(fp_line
			(start -0.508 -0.9398)
			(end 0.508 -0.9398)
			(stroke
				(width 0.1524)
				(type default)
			)
			(layer "B.SilkS")
		)
		(fp_rect
			(start 0.508 0.9398)
			(end -0.508 -0.9398)
			(stroke
				(width 0)
				(type default)
			)
			(fill no)
			(layer "B.CrtYd")
		)
		(fp_rect
			(start 0.508 0.9398)
			(end -0.508 -0.9398)
			(stroke
				(width 0)
				(type default)
			)
			(fill no)
			(layer "B.Fab")
		)
		(pad "1" smd custom
			(at 0 -0.4445 270)
			(size 0.1397 0.1397)
			(layers "B.Cu" "B.Mask" "B.Paste")
			(net "P3V3_STBY")
			(options
				(clearance outline)
				(anchor circle)
			)
			(primitives
				(gr_poly
					(pts
						(arc
							(start -0.1778 0.2794)
							(mid -0.249642 0.249642)
							(end -0.2794 0.1778)
						)
						(arc
							(start -0.2794 -0.1778)
							(mid -0.249642 -0.249642)
							(end -0.1778 -0.2794)
						)
						(arc
							(start 0.1778 -0.2794)
							(mid 0.249642 -0.249642)
							(end 0.2794 -0.1778)
						)
						(arc
							(start 0.2794 0.1778)
							(mid 0.249642 0.249642)
							(end 0.1778 0.2794)
						)
					)
					(width 0)
					(fill yes)
				)
			)
		)
		(pad "2" smd custom
			(at 0 0.4445 270)
			(size 0.1397 0.1397)
			(layers "B.Cu" "B.Mask" "B.Paste")
			(net "ROMD2")
			(options
				(clearance outline)
				(anchor circle)
			)
			(primitives
				(gr_poly
					(pts
						(arc
							(start -0.1778 0.2794)
							(mid -0.249642 0.249642)
							(end -0.2794 0.1778)
						)
						(arc
							(start -0.2794 -0.1778)
							(mid -0.249642 -0.249642)
							(end -0.1778 -0.2794)
						)
						(arc
							(start 0.1778 -0.2794)
							(mid 0.249642 -0.249642)
							(end 0.2794 -0.1778)
						)
						(arc
							(start 0.2794 0.1778)
							(mid 0.249642 0.249642)
							(end 0.1778 0.2794)
						)
					)
					(width 0)
					(fill yes)
				)
			)
		)
	)
	(footprint ""
		(layer "B.Cu")
		(at 162.941 -91.3384 -90)
		(property "Reference" "C720"
			(at 0 0 90)
			(layer "B.SilkS")
			(hide yes)
			(effects
				(font
					(size 1.27 1.27)
				)
				(justify mirror)
			)
		)
		(property "Value" "SC1U10V2KX-4-GP"
			(at -1.1811 -2.7051 270)
			(unlocked yes)
			(layer "B.Fab")
			(hide yes)
			(effects
				(font
					(size 1.016 1.016)
					(thickness 0.1524)
				)
				(justify mirror)
			)
		)
		(property "Device Type" "C402H22"
			(at -1.1811 -4.2291 270)
			(unlocked yes)
			(layer "B.Fab")
			(hide yes)
			(effects
				(font
					(size 1.016 1.016)
					(thickness 0.1524)
				)
				(justify mirror)
			)
		)
		(duplicate_pad_numbers_are_jumpers no)
		(fp_rect
			(start 0.4318 0.9525)
			(end -0.4318 -0.9525)
			(stroke
				(width 0)
				(type default)
			)
			(fill no)
			(layer "B.CrtYd")
		)
		(fp_rect
			(start 0.4318 0.9525)
			(end -0.4318 -0.9525)
			(stroke
				(width 0)
				(type default)
			)
			(fill no)
			(layer "B.Fab")
		)
		(pad "1" smd custom
			(at 0 -0.4445 90)
			(size 0.1524 0.1524)
			(layers "B.Cu" "B.Mask" "B.Paste")
			(net "P1V8_CLKGEN_A")
			(options
				(clearance outline)
				(anchor circle)
			)
			(primitives
				(gr_poly
					(pts
						(arc
							(start 0.3048 0.2032)
							(mid 0.275042 0.275042)
							(end 0.2032 0.3048)
						)
						(arc
							(start -0.2032 0.3048)
							(mid -0.275042 0.275042)
							(end -0.3048 0.2032)
						)
						(arc
							(start -0.3048 -0.2032)
							(mid -0.275042 -0.275042)
							(end -0.2032 -0.3048)
						)
						(arc
							(start 0.2032 -0.3048)
							(mid 0.275042 -0.275042)
							(end 0.3048 -0.2032)
						)
					)
					(width 0)
					(fill yes)
				)
			)
		)
		(pad "2" smd custom
			(at 0 0.4445 90)
			(size 0.1524 0.1524)
			(layers "B.Cu" "B.Mask" "B.Paste")
			(net "GND")
			(options
				(clearance outline)
				(anchor circle)
			)
			(primitives
				(gr_poly
					(pts
						(arc
							(start 0.3048 0.2032)
							(mid 0.275042 0.275042)
							(end 0.2032 0.3048)
						)
						(arc
							(start -0.2032 0.3048)
							(mid -0.275042 0.275042)
							(end -0.3048 0.2032)
						)
						(arc
							(start -0.3048 -0.2032)
							(mid -0.275042 -0.275042)
							(end -0.2032 -0.3048)
						)
						(arc
							(start 0.2032 -0.3048)
							(mid 0.275042 -0.275042)
							(end 0.3048 -0.2032)
						)
					)
					(width 0)
					(fill yes)
				)
			)
		)
	)
	(footprint ""
		(layer "B.Cu")
		(at 272.161 -8.255 90)
		(property "Reference" "R2974"
			(at 0 0 90)
			(layer "B.SilkS")
			(hide yes)
			(effects
				(font
					(size 1.27 1.27)
				)
				(justify mirror)
			)
		)
		(property "Value" "0R2J-2-GP"
			(at -0.064008 -3.993896 90)
			(unlocked yes)
			(layer "B.Fab")
			(hide yes)
			(effects
				(font
					(size 1.016 1.016)
					(thickness 0.1524)
				)
				(justify mirror)
			)
		)
		(property "Device Type" "R402H16"
			(at -0.064008 -5.517896 90)
			(unlocked yes)
			(layer "B.Fab")
			(hide yes)
			(effects
				(font
					(size 1.016 1.016)
					(thickness 0.1524)
				)
				(justify mirror)
			)
		)
		(duplicate_pad_numbers_are_jumpers no)
		(fp_line
			(start 0.508 -0.9398)
			(end 0.508 0.9398)
			(stroke
				(width 0.1524)
				(type default)
			)
			(layer "B.SilkS")
		)
		(fp_line
			(start -0.508 -0.9398)
			(end 0.508 -0.9398)
			(stroke
				(width 0.1524)
				(type default)
			)
			(layer "B.SilkS")
		)
		(fp_rect
			(start 0.508 0.9398)
			(end -0.508 -0.9398)
			(stroke
				(width 0)
				(type default)
			)
			(fill no)
			(layer "B.CrtYd")
		)
		(fp_rect
			(start 0.508 0.9398)
			(end -0.508 -0.9398)
			(stroke
				(width 0)
				(type default)
			)
			(fill no)
			(layer "B.Fab")
		)
		(pad "1" smd custom
			(at 0 -0.4445 270)
			(size 0.1397 0.1397)
			(layers "B.Cu" "B.Mask" "B.Paste")
			(net "PCIE_REFCLK_H0_N")
			(options
				(clearance outline)
				(anchor circle)
			)
			(primitives
				(gr_poly
					(pts
						(arc
							(start -0.1778 0.2794)
							(mid -0.249642 0.249642)
							(end -0.2794 0.1778)
						)
						(arc
							(start -0.2794 -0.1778)
							(mid -0.249642 -0.249642)
							(end -0.1778 -0.2794)
						)
						(arc
							(start 0.1778 -0.2794)
							(mid 0.249642 -0.249642)
							(end 0.2794 -0.1778)
						)
						(arc
							(start 0.2794 0.1778)
							(mid 0.249642 0.249642)
							(end 0.1778 0.2794)
						)
					)
					(width 0)
					(fill yes)
				)
			)
		)
		(pad "2" smd custom
			(at 0 0.4445 270)
			(size 0.1397 0.1397)
			(layers "B.Cu" "B.Mask" "B.Paste")
			(net "PCIE_REFCLK_H0_N_R")
			(options
				(clearance outline)
				(anchor circle)
			)
			(primitives
				(gr_poly
					(pts
						(arc
							(start -0.1778 0.2794)
							(mid -0.249642 0.249642)
							(end -0.2794 0.1778)
						)
						(arc
							(start -0.2794 -0.1778)
							(mid -0.249642 -0.249642)
							(end -0.1778 -0.2794)
						)
						(arc
							(start 0.1778 -0.2794)
							(mid 0.249642 -0.249642)
							(end 0.2794 -0.1778)
						)
						(arc
							(start 0.2794 0.1778)
							(mid 0.249642 0.249642)
							(end 0.1778 0.2794)
						)
					)
					(width 0)
					(fill yes)
				)
			)
		)
	)
)
